FILE_TYPE = CONNECTIVITY;
{Allegro Design Entry HDL 16.6-p007 (v16-6-112F) 10/10/2012}
"PAGE_NUMBER" = 194;
0"NC";
1"GND\g";
2"PVCCIOMCP_CPU0\g";
3"GND\g";
4"GND\g";
5"P12V_STBY\g";
6"P3V3_STBY\g";
7"P5V_STBY\g";
8"GND\g";
9"PVCCMCP_CPU0\g";
10"P1V8_MCP_CPU0\g";
11"P1V8_MCP_CPU0\g";
12"P1V8_MCP_CPU0\g";
13"PVCCIOMCP_CPU0\g";
14"GND\g";
15"PVCCIO_CPU0\g";
16"GND\g";
17"P3V3\g";
18"GND\g";
19"PVCCMCP_CPU0\g"VOLTAGE"1.2V";
20"GND\g";
21"GND\g";
22"GND\g";
23"PVCCMCP_CPU0\g";
24"PVCCMCP_CPU0\g";
25"GND\g";
26"PVCCIOMCP_CPU0\g";
27"FM_P1V8MCP_CPU0_EN";
28"SVID_DIO1_CPU0_R";
29"FM_CPU0_VRM_322M_156M_OSC_EN";
30"VSENSE_PVCCIOMCP_CPU0_SKT_VRTN";
31"VSENSE_PVCCIOMCP_CPU0_SKT_VSEN";
32"VSENSE_P1V8MCP_CPU0_SKT_VRTN";
33"VSENSE_P1V8MCP_CPU0_SKT_VSEN";
34"VSENSE_PVCCMCP_CPU0_SKT_VSEN";
35"CLK_322M_156M_CPU0_OSC_VRM_DP";
36"FM_PVCCIOMCP_CPU0_EN";
37"PWRGD_PVCCIOMCP_CPU0";
38"PWRGD_P1V8MCP_CPU0";
39"SMB_VR_STBY_LVC3_SCL";
40"VSENSE_PVCCMCP_CPU0_SKT_VRTN";
41"CLK_322M_156M_CPU0_OSC_VRM_DN";
42"SVID_DIO0_CPU0_R";
43"SVID_ALERT0_CPU0_R_N";
44"SVID_ALERT1_CPU0_R_N";
45"SMB_VR_STBY_LVC3_SDA";
46"SVID_CLK1_CPU0_R";
47"PWRGD_PVCCMCP_CPU0";
48"FM_PVCCMCP_CPU0_EN";
49"SVID_CLK0_CPU0_R";
50"VR_PVCCIOMCP_CPU0_XADDR1";
51"VR_PVCCMCP_CPU0_XADDR2";
%"GND"
"1","(-1900,2925)","0","mstr_symbols","I100";
;
VOLTAGE"0"
CDS_LIB"mstr_symbols"
BOM_COST"PROC_VRD_VCCIN_CPU0"
SIZE"1B"
ROOM"PVSA_CPU0_DECAP_VR"
BODY_TYPE"PLUMBING"
HDL_POWER"GND";
"A\NAC"1;
%"CAPP"
"1","(-1900,3100)","0","mstr_discrete","I101";
;
CDS_SEC"1"
GROUP"PWR_MCP_CAP"
PART_NUMBER"699013-049"
VALUE"470UF"
LOCATION"C3N14"
TOLERANCE"20%"
VOLTAGE"2.5V"
MATERIAL"ALUM"
PACK_TYPE"3018"
SEC_TYPE"3018"
CDS_LIB"mstr_discrete"
BOM_COST"PROC_VRD_VCCIN_CPU0"
SEC"1"
CDS_LOCATION"C3N14"
ROOM"P0V95_MCP_CPU0_DECAP_VR";
"B"
$PN"2"1;
"A"
$PN"1"2;
%"VCC_CORE"
"1","(-1900,3275)","0","mstr_symbols","I102";
;
HDL_POWER"PVCCIOMCP_CPU0"
VOLTAGE"+0.95"
CDS_LIB"mstr_symbols";
"A"2;
%"GND"
"1","(-7375,1225)","0","mstr_symbols","I110";
;
CDS_LIB"mstr_symbols"
SIZE"1B"
VOLTAGE"0.0V"
BODY_TYPE"PLUMBING"
HDL_POWER"GND";
"A\NAC"3;
%"GND"
"1","(-7225,675)","0","mstr_symbols","I111";
;
SIZE"1B"
CDS_LIB"mstr_symbols"
VOLTAGE"0.0V"
BODY_TYPE"PLUMBING"
HDL_POWER"GND";
"A\NAC"4;
%"P12V_STBY"
"1","(-7175,4075)","0","mstr_symbols","I119";
;
CDS_LIB"mstr_symbols"
SIZE"1B"
VOLTAGE"12.0V"
BODY_TYPE"PLUMBING"
HDL_POWER"P12V_STBY";
"G\NAC"5;
%"P3V3_STBY"
"1","(-5725,3900)","0","mstr_symbols","I120";
;
CDS_LIB"mstr_symbols"
SIZE"1B"
VOLTAGE"+3.3V"
BODY_TYPE"PLUMBING"
HDL_POWER"P3V3_STBY";
"G\NAC"6;
%"P5V_STBY"
"1","(-5775,3200)","0","mstr_symbols","I121";
;
CDS_LIB"mstr_symbols"
SIZE"1B"
VOLTAGE"+5.0V"
BODY_TYPE"PLUMBING"
HDL_POWER"P5V_STBY";
"G\NAC"7;
%"GND"
"1","(-5350,1525)","0","mstr_symbols","I127";
;
SIZE"1B"
CDS_LIB"mstr_symbols"
VOLTAGE"0.0V"
BODY_TYPE"PLUMBING"
HDL_POWER"GND";
"A\NAC"8;
%"VCC_CORE"
"1","(-3900,3925)","0","mstr_symbols","I130";
;
HDL_POWER"PVCCMCP_CPU0"
ROOM"PVMCP_FPGA_CPU0_VR"
CDS_LIB"mstr_symbols"
BOM_COST"PVMCP_FPGA_CPU0_VR";
"A"9;
%"VCC_CORE"
"1","(-4175,4050)","0","mstr_symbols","I141";
;
HDL_POWER"P1V8_MCP_CPU0"
CDS_LIB"mstr_symbols";
"A"10;
%"VCC_CORE"
"1","(-1900,2075)","0","mstr_symbols","I142";
;
HDL_POWER"P1V8_MCP_CPU0"
CDS_LIB"mstr_symbols";
"A"11;
%"VCC_CORE"
"1","(-1300,2075)","0","mstr_symbols","I143";
;
HDL_POWER"P1V8_MCP_CPU0"
CDS_LIB"mstr_symbols";
"A"12;
%"VCC_CORE"
"1","(-5450,2575)","0","mstr_symbols","I144";
;
HDL_POWER"PVCCIOMCP_CPU0"
CDS_LIB"mstr_symbols"
VOLTAGE"+0.95";
"A"13;
%"CAP_A"
"1","(-1600,1850)","0","dev_discrete","I149";
;
GROUP"PWR_MCP_CAP"
PACK_TYPE"0603V"
PART_NUMBER"602433-106"
MATERIAL"X5R"
TOLERANCE"20%"
VOLTAGE"4V"
VALUE"47UF"
LOCATION"C3T1"
CDS_LOCATION"C3T1"
CDS_LIB"dev_discrete"
CDS_SEC"1"
SEC_TYPE"0603V"
SEC"1";
"B"
$PN"2"18;
"A"
$PN"1"11;
%"CAP_A"
"1","(-1900,1850)","0","dev_discrete","I150";
;
GROUP"PWR_MCP_CAP"
LOCATION"C3T2"
VALUE"47UF"
PART_NUMBER"602433-106"
PACK_TYPE"0603V"
VOLTAGE"4V"
TOLERANCE"20%"
MATERIAL"X5R"
CDS_LOCATION"C3T2"
CDS_LIB"dev_discrete"
CDS_SEC"1"
SEC_TYPE"0603V"
SEC"1";
"B"
$PN"2"18;
"A"
$PN"1"11;
%"GND"
"1","(-1300,1575)","0","mstr_symbols","I151";
;
CDS_LIB"mstr_symbols"
SIZE"1B"
VOLTAGE"0"
BODY_TYPE"PLUMBING"
HDL_POWER"GND";
"A\NAC"14;
%"PVCCIO_CPU0"
"1","(-7425,3900)","0","mstr_symbols","I154";
;
CDS_LIB"mstr_symbols"
VOLTAGE"1.1V"
BODY_TYPE"PLUMBING"
HDL_POWER"PVCCIO_CPU0";
"G\NAC"15;
%"RES"
"2","(-7825,100)","0","mstr_discrete","I155";
;
CDS_SEC"1"
CDS_LOCATION"R7C24"
PACK_TYPE"0402"
WATTAGE"1/16W"
MATERIAL"CHIP"
TOLERANCE"1%"
PART_NUMBER"G21796-082"
GROUP"MCP"
LOCATION"R7C24"
VALUE"4.02K"
ROOM"PVCCIN_CPU1_VR"
SEC"1"
CDS_LIB"mstr_discrete"
SEC_TYPE"0402";
"A"
$PN"1"51;
"B"
$PN"2"16;
%"RES"
"2","(-8175,125)","0","mstr_discrete","I156";
;
CDS_SEC"1"
CDS_LOCATION"R3N29"
GROUP"MCP"
PACK_TYPE"0402"
WATTAGE"1/16W"
TOLERANCE"1.0%"
VALUE"16K"
PART_NUMBER"G21796-317"
LOCATION"R3N29"
MATERIAL"CHIP"
ROOM"VDDQ_ABC_PWR_VR"
SEC"1"
CDS_LIB"mstr_discrete"
SEC_TYPE"0402";
"A"
$PN"1"50;
"B"
$PN"2"16;
%"GND"
"1","(-7975,-225)","0","mstr_symbols","I157";
;
SIZE"1B"
CDS_LIB"mstr_symbols"
VOLTAGE"0.0V"
BODY_TYPE"PLUMBING"
HDL_POWER"GND";
"A\NAC"16;
%"CAP_A"
"1","(-1300,1850)","0","dev_discrete","I16";
;
LOCATION"C4T1"
VALUE"1.0UF"
VOLTAGE"6.3V"
GROUP"PWR_MCP_CAP"
MATERIAL"X6S"
PACK_TYPE"0402V"
TOLERANCE"10%"
PART_NUMBER"D97712-004"
ROOM"P1V8_MCP_CPU0"
SEC"1"
SEC_TYPE"0402V"
CDS_SEC"1"
CDS_LIB"dev_discrete"
CDS_LOCATION"C4T1";
"B"
$PN"2"14;
"A"
$PN"1"12;
%"P3V3"
"1","(-7525,3800)","0","mstr_symbols","I170";
;
SIZE"1B"
CDS_LIB"mstr_symbols"
VOLTAGE"+3.3V"
BODY_TYPE"PLUMBING"
HDL_POWER"P3V3";
"G\NAC"17;
%"GND"
"1","(-1900,1575)","0","mstr_symbols","I28";
;
VOLTAGE"0"
SIZE"1B"
CDS_LIB"mstr_symbols"
BODY_TYPE"PLUMBING"
HDL_POWER"GND";
"A\NAC"18;
%"CAPP"
"1","(-1600,2500)","0","mstr_discrete","I29";
;
CDS_SEC"1"
LOCATION"C4R1"
VALUE"470UF"
GROUP"PWR_MCP_CAP"
PACK_TYPE"3018"
TOLERANCE"20%"
VOLTAGE"2.5V"
MATERIAL"ALUM"
PART_NUMBER"699013-049"
CDS_LIB"mstr_discrete"
BOM_COST"PVMCP_MCP_CPU0_VR"
SEC_TYPE"3018"
SEC"1"
CDS_LOCATION"C4R1"
ROOM"PVMCP_MCP_CPU0_VR";
"B"
$PN"2"20;
"A"
$PN"1"19;
%"VCC_CORE"
"1","(-1900,2725)","0","mstr_symbols","I30";
;
HDL_POWER"PVCCMCP_CPU0"
CDS_LIB"mstr_symbols"
BOM_COST"PVMCP_FPGA_CPU0_VR"
ROOM"PVMCP_FPGA_CPU0_VR";
"A"19;
%"CAPP"
"1","(-1900,2500)","0","mstr_discrete","I31";
;
GROUP"PWR_MCP_CAP"
PACK_TYPE"3018"
TOLERANCE"20%"
LOCATION"C3R4"
PART_NUMBER"699013-049"
VALUE"470UF"
VOLTAGE"2.5V"
MATERIAL"ALUM"
ROOM"PVMCP_MCP_CPU0_VR"
CDS_LOCATION"C3R4"
$SEC"1"
CDS_SEC"1"
BOM_COST"PVMCP_MCP_CPU0_VR"
CDS_LIB"mstr_discrete";
"B"
$PN"2"20;
"A"
$PN"1"19;
%"GND"
"1","(-1900,2225)","0","mstr_symbols","I33";
;
ROOM"PVMCP_FPGA_CPU0_VR"
BOM_COST"PVMCP_FPGA_CPU0_VR"
SIZE"1B"
CDS_LIB"mstr_symbols"
VOLTAGE"0.0V"
BODY_TYPE"PLUMBING"
HDL_POWER"GND";
"A\NAC"20;
%"SCONN120_H61426002"
"1","(-3150,2100)","0","mstr_sconn","I55";
;
CDS_SEC"1"
LOCATION"J6E1"
MATERIAL"CONN"
ROOM"MCP VRM CPU0"
PART_NUMBER"H61426-002"
GROUP"MCP"
CDS_LOCATION"J6E1"
SEC"1"
CDS_LIB"mstr_sconn"
SEC_TYPE"SM"
PACK_TYPE"SM";
"IOB11"
$PN"B11"24;
"IOA1"
$PN"A1"9;
"IOB1"
$PN"B1"9;
"IOD1"
$PN"D1"33;
"IOC1"
$PN"C1"9;
"IOE1"
$PN"E1"10;
"IOF1"
$PN"F1"10;
"IOB2"
$PN"B2"9;
"IOA2"
$PN"A2"9;
"IOC2"
$PN"C2"9;
"IOD2"
$PN"D2"32;
"IOE2"
$PN"E2"10;
"IOF2"
$PN"F2"10;
"IOB3"
$PN"B3"9;
"IOA3"
$PN"A3"9;
"IOC3"
$PN"C3"9;
"IOD3"
$PN"D3"10;
"IOE3"
$PN"E3"10;
"IOF3"
$PN"F3"10;
"IOA4"
$PN"A4"34;
"IOB4"
$PN"B4"40;
"IOC4"
$PN"C4"23;
"IOD4"
$PN"D4"21;
"IOF4"
$PN"F4"21;
"IOE4"
$PN"E4"21;
"IOA5"
$PN"A5"23;
"IOB5"
$PN"B5"23;
"IOD5"
$PN"D5"21;
"IOC5"
$PN"C5"23;
"IOF5"
$PN"F5"41;
"IOE5"
$PN"E5"35;
"IOA6"
$PN"A6"23;
"IOB6"
$PN"B6"23;
"IOD6"
$PN"D6"21;
"IOC6"
$PN"C6"23;
"IOE6"
$PN"E6"21;
"IOF6"
$PN"F6"21;
"IOA7"
$PN"A7"23;
"IOC7"
$PN"C7"23;
"IOB7"
$PN"B7"23;
"IOE7"
$PN"E7"21;
"IOD7"
$PN"D7"21;
"IOF7"
$PN"F7"21;
"IOA8"
$PN"A8"23;
"IOB8"
$PN"B8"23;
"IOC8"
$PN"C8"23;
"IOD8"
$PN"D8"21;
"IOF8"
$PN"F8"21;
"IOE8"
$PN"E8"21;
"IOB9"
$PN"B9"23;
"IOA9"
$PN"A9"23;
"IOC9"
$PN"C9"23;
"IOD9"
$PN"D9"21;
"IOE9"
$PN"E9"21;
"IOF9"
$PN"F9"21;
"IOA10"
$PN"A10"23;
"IOB10"
$PN"B10"23;
"IOC10"
$PN"C10"23;
"IOE10"
$PN"E10"21;
"IOD10"
$PN"D10"21;
"IOF10"
$PN"F10"21;
"IOA11"
$PN"A11"24;
"IOC11"
$PN"C11"24;
"IOD11"
$PN"D11"22;
"IOE11"
$PN"E11"22;
"IOF11"
$PN"F11"22;
"IOA12"
$PN"A12"24;
"IOB12"
$PN"B12"24;
"IOD12"
$PN"D12"22;
"IOC12"
$PN"C12"24;
"IOF12"
$PN"F12"22;
"IOE12"
$PN"E12"22;
"IOA13"
$PN"A13"24;
"IOB13"
$PN"B13"24;
"IOC13"
$PN"C13"24;
"IOE13"
$PN"E13"22;
"IOD13"
$PN"D13"22;
"IOF13"
$PN"F13"22;
"IOA14"
$PN"A14"24;
"IOC14"
$PN"C14"24;
"IOB14"
$PN"B14"24;
"IOE14"
$PN"E14"22;
"IOD14"
$PN"D14"22;
"IOF14"
$PN"F14"22;
"IOA15"
$PN"A15"24;
"IOB15"
$PN"B15"24;
"IOC15"
$PN"C15"24;
"IOD15"
$PN"D15"22;
"IOF15"
$PN"F15"22;
"IOE15"
$PN"E15"22;
"IOA16"
$PN"A16"24;
"IOB16"
$PN"B16"24;
"IOC16"
$PN"C16"24;
"IOD16"
$PN"D16"22;
"IOE16"
$PN"E16"22;
"IOF16"
$PN"F16"22;
"IOA17"
$PN"A17"24;
"IOB17"
$PN"B17"24;
"IOC17"
$PN"C17"24;
"IOD17"
$PN"D17"22;
"IOE17"
$PN"E17"22;
"IOF17"
$PN"F17"22;
"IOA18"
$PN"A18"24;
"IOC18"
$PN"C18"24;
"IOB18"
$PN"B18"24;
"IOD18"
$PN"D18"22;
"IOE18"
$PN"E18"22;
"IOF18"
$PN"F18"22;
"IOA19"
$PN"A19"22;
"IOB19"
$PN"B19"22;
"IOD19"
$PN"D19"22;
"IOC19"
$PN"C19"22;
"IOF19"
$PN"F19"22;
"IOE19"
$PN"E19"22;
"IOB20"
$PN"B20"22;
"IOA20"
$PN"A20"22;
"IOD20"
$PN"D20"22;
"IOC20"
$PN"C20"22;
"IOE20"
$PN"E20"22;
"IOF20"
$PN"F20"22;
%"SCONN120_H61426002"
"1","(-6550,2075)","0","mstr_sconn","I56";
;
CDS_SEC"1"
ROOM"MCP VRM CPU0"
MATERIAL"CONN"
LOCATION"J6B1"
GROUP"MCP"
PART_NUMBER"H61426-002"
CDS_LOCATION"J6B1"
SEC"1"
CDS_LIB"mstr_sconn"
SEC_TYPE"SM"
PACK_TYPE"SM";
"IOB11"
$PN"B11"6;
"IOA1"
$PN"A1"5;
"IOB1"
$PN"B1"5;
"IOD1"
$PN"D1"17;
"IOC1"
$PN"C1"3;
"IOE1"
$PN"E1"29;
"IOF1"
$PN"F1"15;
"IOB2"
$PN"B2"5;
"IOA2"
$PN"A2"5;
"IOC2"
$PN"C2"3;
"IOD2"
$PN"D2"3;
"IOE2"
$PN"E2"3;
"IOF2"
$PN"F2"3;
"IOB3"
$PN"B3"5;
"IOA3"
$PN"A3"5;
"IOC3"
$PN"C3"3;
"IOD3"
$PN"D3"3;
"IOE3"
$PN"E3"3;
"IOF3"
$PN"F3"3;
"IOA4"
$PN"A4"5;
"IOB4"
$PN"B4"5;
"IOC4"
$PN"C4"3;
"IOD4"
$PN"D4"3;
"IOF4"
$PN"F4"3;
"IOE4"
$PN"E4"3;
"IOA5"
$PN"A5"5;
"IOB5"
$PN"B5"5;
"IOD5"
$PN"D5"3;
"IOC5"
$PN"C5"3;
"IOF5"
$PN"F5"3;
"IOE5"
$PN"E5"3;
"IOA6"
$PN"A6"5;
"IOB6"
$PN"B6"5;
"IOD6"
$PN"D6"3;
"IOC6"
$PN"C6"3;
"IOE6"
$PN"E6"3;
"IOF6"
$PN"F6"3;
"IOA7"
$PN"A7"5;
"IOC7"
$PN"C7"3;
"IOB7"
$PN"B7"5;
"IOE7"
$PN"E7"3;
"IOD7"
$PN"D7"3;
"IOF7"
$PN"F7"3;
"IOA8"
$PN"A8"5;
"IOB8"
$PN"B8"5;
"IOC8"
$PN"C8"4;
"IOD8"
$PN"D8"4;
"IOF8"
$PN"F8"30;
"IOE8"
$PN"E8"31;
"IOB9"
$PN"B9"4;
"IOA9"
$PN"A9"4;
"IOC9"
$PN"C9"4;
"IOD9"
$PN"D9"4;
"IOE9"
$PN"E9"4;
"IOF9"
$PN"F9"4;
"IOA10"
$PN"A10"4;
"IOB10"
$PN"B10"4;
"IOC10"
$PN"C10"4;
"IOE10"
$PN"E10"50;
"IOD10"
$PN"D10"4;
"IOF10"
$PN"F10"51;
"IOA11"
$PN"A11"6;
"IOC11"
$PN"C11"6;
"IOD11"
$PN"D11"8;
"IOE11"
$PN"E11"8;
"IOF11"
$PN"F11"8;
"IOA12"
$PN"A12"8;
"IOB12"
$PN"B12"8;
"IOD12"
$PN"D12"8;
"IOC12"
$PN"C12"8;
"IOF12"
$PN"F12"8;
"IOE12"
$PN"E12"8;
"IOA13"
$PN"A13"7;
"IOB13"
$PN"B13"7;
"IOC13"
$PN"C13"7;
"IOE13"
$PN"E13"8;
"IOD13"
$PN"D13"8;
"IOF13"
$PN"F13"8;
"IOA14"
$PN"A14"8;
"IOC14"
$PN"C14"8;
"IOB14"
$PN"B14"8;
"IOE14"
$PN"E14"8;
"IOD14"
$PN"D14"8;
"IOF14"
$PN"F14"8;
"IOA15"
$PN"A15"27;
"IOB15"
$PN"B15"38;
"IOC15"
$PN"C15"8;
"IOD15"
$PN"D15"8;
"IOF15"
$PN"F15"13;
"IOE15"
$PN"E15"13;
"IOA16"
$PN"A16"36;
"IOB16"
$PN"B16"37;
"IOC16"
$PN"C16"8;
"IOD16"
$PN"D16"8;
"IOE16"
$PN"E16"13;
"IOF16"
$PN"F16"13;
"IOA17"
$PN"A17"8;
"IOB17"
$PN"B17"8;
"IOC17"
$PN"C17"13;
"IOD17"
$PN"D17"13;
"IOE17"
$PN"E17"13;
"IOF17"
$PN"F17"13;
"IOA18"
$PN"A18"39;
"IOC18"
$PN"C18"13;
"IOB18"
$PN"B18"45;
"IOD18"
$PN"D18"13;
"IOE18"
$PN"E18"13;
"IOF18"
$PN"F18"13;
"IOA19"
$PN"A19"43;
"IOB19"
$PN"B19"44;
"IOD19"
$PN"D19"13;
"IOC19"
$PN"C19"13;
"IOF19"
$PN"F19"13;
"IOE19"
$PN"E19"13;
"IOB20"
$PN"B20"42;
"IOA20"
$PN"A20"49;
"IOD20"
$PN"D20"47;
"IOC20"
$PN"C20"48;
"IOE20"
$PN"E20"46;
"IOF20"
$PN"F20"28;
%"GND"
"1","(-3975,225)","0","mstr_symbols","I61";
;
SIZE"1B"
CDS_LIB"mstr_symbols"
VOLTAGE"0.0V"
BODY_TYPE"PLUMBING"
HDL_POWER"GND";
"A\NAC"21;
%"GND"
"1","(-2150,200)","0","mstr_symbols","I62";
;
CDS_LIB"mstr_symbols"
SIZE"1B"
VOLTAGE"0.0V"
BODY_TYPE"PLUMBING"
HDL_POWER"GND";
"A\NAC"22;
%"VCC_CORE"
"1","(-5125,3075)","0","mstr_symbols","I68";
;
HDL_POWER"PVCCMCP_CPU0"
BOM_COST"PVMCP_FPGA_CPU0_VR"
CDS_LIB"mstr_symbols"
ROOM"PVMCP_FPGA_CPU0_VR";
"A"23;
%"VCC_CORE"
"1","(-2300,3925)","0","mstr_symbols","I69";
;
HDL_POWER"PVCCMCP_CPU0"
ROOM"PVMCP_FPGA_CPU0_VR"
CDS_LIB"mstr_symbols"
BOM_COST"PVMCP_FPGA_CPU0_VR";
"A"24;
%"CAP_A"
"1","(-1100,3100)","0","dev_discrete","I86";
;
CDS_LOCATION"C3N40"
GROUP"PWR_MCP_CAP"
LOCATION"C3N40"
VALUE"1.0UF"
VOLTAGE"6.3V"
TOLERANCE"10%"
MATERIAL"X6S"
PART_NUMBER"D97712-004"
PACK_TYPE"0402V"
CDS_LIB"dev_discrete"
CDS_SEC"1"
SEC_TYPE"0402V"
SEC"1"
ROOM"P0V95_MCP_CPU0";
"B"
$PN"2"25;
"A"
$PN"1"26;
%"CAP_A"
"1","(-1000,1850)","0","dev_discrete","I9";
;
MATERIAL"X6S"
PART_NUMBER"D97712-004"
GROUP"PWR_MCP_CAP"
VOLTAGE"6.3V"
PACK_TYPE"0402V"
TOLERANCE"10%"
VALUE"1.0UF"
LOCATION"C4T2"
ROOM"P1V8_MCP_CPU0"
SEC"1"
SEC_TYPE"0402V"
CDS_SEC"1"
CDS_LIB"dev_discrete"
CDS_LOCATION"C4T2";
"B"
$PN"2"14;
"A"
$PN"1"12;
%"GND"
"1","(-1400,2825)","0","mstr_symbols","I92";
;
CDS_LIB"mstr_symbols"
SIZE"1B"
VOLTAGE"0.0V"
BODY_TYPE"PLUMBING"
HDL_POWER"GND";
"A\NAC"25;
%"VCC_CORE"
"1","(-1400,3325)","0","mstr_symbols","I95";
;
HDL_POWER"PVCCIOMCP_CPU0"
CDS_LIB"mstr_symbols";
"A"26;
%"CAP_A"
"1","(-1400,3100)","0","dev_discrete","I99";
;
CDS_LOCATION"C3M46"
GROUP"PWR_MCP_CAP"
LOCATION"C3M46"
PART_NUMBER"D97712-004"
PACK_TYPE"0402V"
VOLTAGE"6.3V"
VALUE"1.0UF"
MATERIAL"X6S"
TOLERANCE"10%"
ROOM"P0V95_MCP_CPU0"
SEC"1"
SEC_TYPE"0402V"
CDS_SEC"1"
CDS_LIB"dev_discrete";
"B"
$PN"2"25;
"A"
$PN"1"26;
END.
